# S9S_MB_2U (Grand Teton) — schematic netlist excerpt (pin names and nets, part order shuffled) for the footprints in the layout excerpt that follows; sources: Cadence DE-HDL packaged netlist, KiCad conversion of 03242023_DA0F0TMBIJ0_F0T_Motherboard_J_brd_V01_OCP.brd

PC1286  Q_CAP  22UF 4V 20% X6S  pkg C0805  page 300 : A = PVNN_MAIN_CPU1 ; B = GND
PR144  Q_RES  8.87K 1% EMPTY  pkg 0402LF  page 268 : A = PVCCIN_CPU0_LSET4 ; B = GND

U339  AP331AWG7  AP331AWG-7 EMPTY  pkg SOT25  page 307
  \in-\  = UV_ADR_P2V5_COMP
  GND  = GND
  \in+\  = P12V_AUX_UV_ADR_TRIGGER
  OUTPUT  = FM_UV_ADR_TRIGGER_N_R2
  VCC  = P12V_AUX

(kicad_pcb
	(version 20260206)
	(generator "pcbnew")
	(generator_version "10.0")
	(general
		(thickness 1.6)
		(legacy_teardrops no)
	)
	(paper "A4")
	(title_block
		(title "03242023_DA0F0TMBIJ0_F0T_Motherboard_J_brd_V01_OCP.brd")
		(comment 1 "Grand Teton / footprints 2941-2943 of 6105")
	)
	(layers
		(0 "F.Cu" signal "TOP")
		(4 "In1.Cu" signal "GND")
		(6 "In2.Cu" signal "IN1")
		(8 "In3.Cu" signal "GND1")
		(10 "In4.Cu" signal "IN2")
		(12 "In5.Cu" signal "GND2")
		(14 "In6.Cu" signal "IN3")
		(16 "In7.Cu" signal "GND3")
		(18 "In8.Cu" signal "VCC")
		(20 "In9.Cu" signal "VCC1")
		(22 "In10.Cu" signal "GND4")
		(24 "In11.Cu" signal "IN4")
		(26 "In12.Cu" signal "GND5")
		(28 "In13.Cu" signal "IN5")
		(30 "In14.Cu" signal "GND6")
		(32 "In15.Cu" signal "IN6")
		(34 "In16.Cu" signal "GND7")
		(2 "B.Cu" signal "BOTTOM")
		(9 "F.Adhes" user "F.Adhesive")
		(11 "B.Adhes" user "B.Adhesive")
		(13 "F.Paste" user "Package Geometry/Pastemask Top")
		(15 "B.Paste" user "Package Geometry/Pastemask Bottom")
		(5 "F.SilkS" user "Ref Des/Silkscreen Top")
		(7 "B.SilkS" user "Ref Des/Silkscreen Bottom")
		(1 "F.Mask" user "Board Geometry/Soldermask Top")
		(3 "B.Mask" user "Board Geometry/Soldermask Bottom")
		(17 "Dwgs.User" user "User.Drawings")
		(19 "Cmts.User" user "User.Comments")
		(21 "Eco1.User" user "User.Eco1")
		(23 "Eco2.User" user "User.Eco2")
		(25 "Edge.Cuts" user "Board Geometry/Outline")
		(27 "Margin" user)
		(31 "F.CrtYd" user "Package Geometry/Place Bound Top")
		(29 "B.CrtYd" user "Package Geometry/Place Bound Bottom")
		(35 "F.Fab" user "Ref Des/Assembly Top")
		(33 "B.Fab" user "Ref Des/Assembly Bottom")
	)
	(footprint ""
		(layer "F.Cu")
		(at 368.127788 -338.86013)
		(property "Reference" "PR144"
			(at 0 0 0)
			(layer "F.SilkS")
			(hide yes)
			(effects
				(font
					(size 1.27 1.27)
				)
			)
		)
		(property "Value" ""
			(at 0 0 0)
			(layer "F.Fab")
			(effects
				(font
					(size 1.27 1.27)
				)
			)
		)
		(duplicate_pad_numbers_are_jumpers no)
		(fp_line
			(start -0.7874 -0.4064)
			(end 0.7874 -0.4064)
			(stroke
				(width 0.1524)
				(type default)
			)
			(layer "F.SilkS")
		)
		(fp_line
			(start -0.7874 0.4064)
			(end -0.7874 -0.4064)
			(stroke
				(width 0.1524)
				(type default)
			)
			(layer "F.SilkS")
		)
		(fp_line
			(start 0.7874 -0.4064)
			(end 0.7874 0.4064)
			(stroke
				(width 0.1524)
				(type default)
			)
			(layer "F.SilkS")
		)
		(fp_line
			(start 0.7874 0.4064)
			(end -0.7874 0.4064)
			(stroke
				(width 0.1524)
				(type default)
			)
			(layer "F.SilkS")
		)
		(fp_line
			(start -0.67945 -0.305054)
			(end -0.12065 -0.305054)
			(stroke
				(width 0.1)
				(type default)
			)
			(layer "F.Fab")
		)
		(fp_line
			(start -0.67945 0.3048)
			(end -0.67945 -0.305054)
			(stroke
				(width 0.1)
				(type default)
			)
			(layer "F.Fab")
		)
		(fp_line
			(start -0.12065 -0.305054)
			(end -0.12065 -0.2794)
			(stroke
				(width 0.1)
				(type default)
			)
			(layer "F.Fab")
		)
		(fp_line
			(start -0.12065 -0.2794)
			(end 0.12065 -0.2794)
			(stroke
				(width 0.1)
				(type default)
			)
			(layer "F.Fab")
		)
		(fp_line
			(start -0.12065 0.2794)
			(end -0.12065 0.3048)
			(stroke
				(width 0.1)
				(type default)
			)
			(layer "F.Fab")
		)
		(fp_line
			(start -0.12065 0.3048)
			(end -0.67945 0.3048)
			(stroke
				(width 0.1)
				(type default)
			)
			(layer "F.Fab")
		)
		(fp_line
			(start 0.120396 0.2794)
			(end -0.12065 0.2794)
			(stroke
				(width 0.1)
				(type default)
			)
			(layer "F.Fab")
		)
		(fp_line
			(start 0.120396 0.3048)
			(end 0.120396 0.2794)
			(stroke
				(width 0.1)
				(type default)
			)
			(layer "F.Fab")
		)
		(fp_line
			(start 0.12065 -0.3048)
			(end 0.67945 -0.3048)
			(stroke
				(width 0.1)
				(type default)
			)
			(layer "F.Fab")
		)
		(fp_line
			(start 0.12065 -0.2794)
			(end 0.12065 -0.3048)
			(stroke
				(width 0.1)
				(type default)
			)
			(layer "F.Fab")
		)
		(fp_line
			(start 0.67945 -0.3048)
			(end 0.67945 0.3048)
			(stroke
				(width 0.1)
				(type default)
			)
			(layer "F.Fab")
		)
		(fp_line
			(start 0.67945 0.3048)
			(end 0.120396 0.3048)
			(stroke
				(width 0.1)
				(type default)
			)
			(layer "F.Fab")
		)
		(pad "1" smd circle
			(at -0.40005 0)
			(size 0 0)
			(layers "F.Cu" "F.Mask" "F.Paste")
			(net "PVCCIN_CPU0_LSET4")
		)
		(pad "2" smd circle
			(at 0.40005 0)
			(size 0 0)
			(layers "F.Cu" "F.Mask" "F.Paste")
			(net "GND")
		)
	)
	(footprint ""
		(layer "F.Cu")
		(at 203.1492 -95.91802 90)
		(property "Reference" "U339"
			(at -0.8382 2.13487 90)
			(unlocked yes)
			(layer "F.SilkS")
			(effects
				(font
					(size 0.7874 0.5842)
					(thickness 0.1524)
				)
			)
		)
		(property "Value" ""
			(at 0 0 90)
			(layer "F.Fab")
			(effects
				(font
					(size 1.27 1.27)
				)
			)
		)
		(duplicate_pad_numbers_are_jumpers no)
		(fp_line
			(start 2.032 -1.549908)
			(end 2.032 1.549908)
			(stroke
				(width 0.1524)
				(type default)
			)
			(layer "F.SilkS")
		)
		(fp_line
			(start 0.508 -1.549908)
			(end 2.032 -1.549908)
			(stroke
				(width 0.1524)
				(type default)
			)
			(layer "F.SilkS")
		)
		(fp_line
			(start -0.508 -1.549908)
			(end 0 -0.762)
			(stroke
				(width 0.1524)
				(type default)
			)
			(layer "F.SilkS")
		)
		(fp_line
			(start -2.032 -1.549908)
			(end -0.508 -1.549908)
			(stroke
				(width 0.1524)
				(type default)
			)
			(layer "F.SilkS")
		)
		(fp_line
			(start 0 -0.762)
			(end 0.508 -1.549908)
			(stroke
				(width 0.1524)
				(type default)
			)
			(layer "F.SilkS")
		)
		(fp_line
			(start 2.032 1.549908)
			(end -2.032 1.549908)
			(stroke
				(width 0.1524)
				(type default)
			)
			(layer "F.SilkS")
		)
		(fp_line
			(start -2.032 1.549908)
			(end -2.032 -1.549908)
			(stroke
				(width 0.1524)
				(type default)
			)
			(layer "F.SilkS")
		)
		(fp_poly
			(pts
				(xy -3.2004 -1.45796) (xy -3.2004 -0.44196) (xy -2.1844 -0.94996)
			)
			(stroke
				(width 0)
				(type default)
			)
			(fill yes)
			(layer "F.SilkS")
		)
		(fp_line
			(start 0.849884 -1.549908)
			(end 0.849884 1.549908)
			(stroke
				(width 0.1)
				(type default)
			)
			(layer "F.Fab")
		)
		(fp_line
			(start -0.849884 -1.549908)
			(end 0.849884 -1.549908)
			(stroke
				(width 0.1)
				(type default)
			)
			(layer "F.Fab")
		)
		(fp_line
			(start 0.849884 1.549908)
			(end -0.849884 1.549908)
			(stroke
				(width 0.1)
				(type default)
			)
			(layer "F.Fab")
		)
		(fp_line
			(start -0.849884 1.549908)
			(end -0.849884 -1.549908)
			(stroke
				(width 0.1)
				(type default)
			)
			(layer "F.Fab")
		)
		(fp_poly
			(pts
				(xy -3.2004 -1.45796) (xy -3.2004 -0.44196) (xy -2.1844 -0.94996)
			)
			(stroke
				(width 0)
				(type default)
			)
			(fill yes)
			(layer "F.Fab")
		)
		(pad "1" smd rect
			(at -1.35001 -0.94996)
			(size 0.6096 1.0668)
			(layers "F.Cu" "F.Mask" "F.Paste")
			(net "UV_ADR_P2V5_COMP")
		)
		(pad "2" smd rect
			(at -1.35001 0)
			(size 0.6096 1.0668)
			(layers "F.Cu" "F.Mask" "F.Paste")
			(net "GND")
		)
		(pad "3" smd rect
			(at -1.35001 0.94996)
			(size 0.6096 1.0668)
			(layers "F.Cu" "F.Mask" "F.Paste")
			(net "P12V_AUX_UV_ADR_TRIGGER")
		)
		(pad "4" smd rect
			(at 1.35001 0.94996)
			(size 0.6096 1.0668)
			(layers "F.Cu" "F.Mask" "F.Paste")
			(net "FM_UV_ADR_TRIGGER_N_R2")
		)
		(pad "5" smd rect
			(at 1.35001 -0.94996)
			(size 0.6096 1.0668)
			(layers "F.Cu" "F.Mask" "F.Paste")
			(net "P12V_AUX")
		)
	)
	(footprint ""
		(layer "F.Cu")
		(at 36.795202 -180.55336)
		(property "Reference" "PC1286"
			(at 0 0 0)
			(layer "F.SilkS")
			(hide yes)
			(effects
				(font
					(size 1.27 1.27)
				)
			)
		)
		(property "Value" ""
			(at 0 0 0)
			(layer "F.Fab")
			(effects
				(font
					(size 1.27 1.27)
				)
			)
		)
		(duplicate_pad_numbers_are_jumpers no)
		(fp_line
			(start -1.524 -0.762)
			(end 1.524 -0.762)
			(stroke
				(width 0.1524)
				(type default)
			)
			(layer "F.SilkS")
		)
		(fp_line
			(start -1.524 0.762)
			(end -1.524 -0.762)
			(stroke
				(width 0.1524)
				(type default)
			)
			(layer "F.SilkS")
		)
		(fp_line
			(start 1.524 -0.762)
			(end 1.524 0.762)
			(stroke
				(width 0.1524)
				(type default)
			)
			(layer "F.SilkS")
		)
		(fp_line
			(start 1.524 0.762)
			(end -1.524 0.762)
			(stroke
				(width 0.1524)
				(type default)
			)
			(layer "F.SilkS")
		)
		(fp_line
			(start -1.1049 -0.724916)
			(end -1.1049 0.724916)
			(stroke
				(width 0.1)
				(type default)
			)
			(layer "F.Fab")
		)
		(fp_line
			(start -1.1049 0.724916)
			(end 1.1049 0.724916)
			(stroke
				(width 0.1)
				(type default)
			)
			(layer "F.Fab")
		)
		(fp_line
			(start 1.1049 -0.724916)
			(end -1.1049 -0.724916)
			(stroke
				(width 0.1)
				(type default)
			)
			(layer "F.Fab")
		)
		(fp_line
			(start 1.1049 0.724916)
			(end 1.1049 -0.724916)
			(stroke
				(width 0.1)
				(type default)
			)
			(layer "F.Fab")
		)
		(pad "1" smd rect
			(at -0.889 0 180)
			(size 1.016 1.27)
			(layers "F.Cu" "F.Mask" "F.Paste")
			(net "PVNN_MAIN_CPU1")
		)
		(pad "2" smd rect
			(at 0.889 0 180)
			(size 1.016 1.27)
			(layers "F.Cu" "F.Mask" "F.Paste")
			(net "GND")
		)
	)
)
